(kicad_pcb
	(version 20260206)
	(generator "pcbnew")
	(generator_version "10.0")
	(general
		(thickness 1.6)
		(legacy_teardrops no)
	)
	(paper "A4")
	(title_block
		(title "01162023_DA0F0TEBIF0_F0T_Expander_BD_F_brd_V02_OCP.brd")
		(comment 1 "Grand Teton / footprints 3955-3959 of 9728")
	)
	(layers
		(0 "F.Cu" signal "TOP")
		(4 "In1.Cu" signal "GND")
		(6 "In2.Cu" signal "VCC")
		(8 "In3.Cu" signal "VCC1")
		(10 "In4.Cu" signal "GND1")
		(12 "In5.Cu" signal "IN1")
		(14 "In6.Cu" signal "GND2")
		(16 "In7.Cu" signal "IN2")
		(18 "In8.Cu" signal "GND3")
		(20 "In9.Cu" signal "IN3")
		(22 "In10.Cu" signal "GND4")
		(24 "In11.Cu" signal "IN4")
		(26 "In12.Cu" signal "GND5")
		(28 "In13.Cu" signal "IN5")
		(30 "In14.Cu" signal "GND6")
		(32 "In15.Cu" signal "IN6")
		(34 "In16.Cu" signal "GND7")
		(2 "B.Cu" signal "BOTTOM")
		(9 "F.Adhes" user "F.Adhesive")
		(11 "B.Adhes" user "B.Adhesive")
		(13 "F.Paste" user "Package Geometry/Pastemask Top")
		(15 "B.Paste" user "Package Geometry/Pastemask Bottom")
		(5 "F.SilkS" user "Ref Des/Silkscreen Top")
		(7 "B.SilkS" user "Ref Des/Silkscreen Bottom")
		(1 "F.Mask" user "Board Geometry/Soldermask Top")
		(3 "B.Mask" user "Board Geometry/Soldermask Bottom")
		(17 "Dwgs.User" user "User.Drawings")
		(19 "Cmts.User" user "User.Comments")
		(21 "Eco1.User" user "User.Eco1")
		(23 "Eco2.User" user "User.Eco2")
		(25 "Edge.Cuts" user "Board Geometry/Outline")
		(27 "Margin" user)
		(31 "F.CrtYd" user "Package Geometry/Place Bound Top")
		(29 "B.CrtYd" user "Package Geometry/Place Bound Bottom")
		(35 "F.Fab" user "Ref Des/Assembly Top")
		(33 "B.Fab" user "Ref Des/Assembly Bottom")
	)
	(footprint ""
		(layer "F.Cu")
		(at 12.807696 -302.8315)
		(property "Reference" "PC211"
			(at 0 0 0)
			(layer "F.SilkS")
			(hide yes)
			(effects
				(font
					(size 1.27 1.27)
				)
			)
		)
		(property "Value" ""
			(at 0 0 0)
			(layer "F.Fab")
			(effects
				(font
					(size 1.27 1.27)
				)
			)
		)
		(duplicate_pad_numbers_are_jumpers no)
		(fp_line
			(start -0.7874 -0.4064)
			(end 0.7874 -0.4064)
			(stroke
				(width 0.1524)
				(type default)
			)
			(layer "F.SilkS")
		)
		(fp_line
			(start -0.7874 0.4064)
			(end -0.7874 -0.4064)
			(stroke
				(width 0.1524)
				(type default)
			)
			(layer "F.SilkS")
		)
		(fp_line
			(start 0.7874 -0.4064)
			(end 0.7874 0.4064)
			(stroke
				(width 0.1524)
				(type default)
			)
			(layer "F.SilkS")
		)
		(fp_line
			(start 0.7874 0.4064)
			(end -0.7874 0.4064)
			(stroke
				(width 0.1524)
				(type default)
			)
			(layer "F.SilkS")
		)
		(fp_line
			(start -0.67945 -0.305054)
			(end -0.12065 -0.305054)
			(stroke
				(width 0.1)
				(type default)
			)
			(layer "F.Fab")
		)
		(fp_line
			(start -0.67945 0.3048)
			(end -0.67945 -0.305054)
			(stroke
				(width 0.1)
				(type default)
			)
			(layer "F.Fab")
		)
		(fp_line
			(start -0.12065 -0.305054)
			(end -0.12065 -0.2794)
			(stroke
				(width 0.1)
				(type default)
			)
			(layer "F.Fab")
		)
		(fp_line
			(start -0.12065 -0.2794)
			(end 0.12065 -0.2794)
			(stroke
				(width 0.1)
				(type default)
			)
			(layer "F.Fab")
		)
		(fp_line
			(start -0.12065 0.2794)
			(end -0.12065 0.3048)
			(stroke
				(width 0.1)
				(type default)
			)
			(layer "F.Fab")
		)
		(fp_line
			(start -0.12065 0.3048)
			(end -0.67945 0.3048)
			(stroke
				(width 0.1)
				(type default)
			)
			(layer "F.Fab")
		)
		(fp_line
			(start 0.120396 0.2794)
			(end -0.12065 0.2794)
			(stroke
				(width 0.1)
				(type default)
			)
			(layer "F.Fab")
		)
		(fp_line
			(start 0.120396 0.3048)
			(end 0.120396 0.2794)
			(stroke
				(width 0.1)
				(type default)
			)
			(layer "F.Fab")
		)
		(fp_line
			(start 0.12065 -0.3048)
			(end 0.67945 -0.3048)
			(stroke
				(width 0.1)
				(type default)
			)
			(layer "F.Fab")
		)
		(fp_line
			(start 0.12065 -0.2794)
			(end 0.12065 -0.3048)
			(stroke
				(width 0.1)
				(type default)
			)
			(layer "F.Fab")
		)
		(fp_line
			(start 0.67945 -0.3048)
			(end 0.67945 0.3048)
			(stroke
				(width 0.1)
				(type default)
			)
			(layer "F.Fab")
		)
		(fp_line
			(start 0.67945 0.3048)
			(end 0.120396 0.3048)
			(stroke
				(width 0.1)
				(type default)
			)
			(layer "F.Fab")
		)
		(pad "1" smd circle
			(at -0.40005 0)
			(size 0 0)
			(layers "F.Cu" "F.Mask" "F.Paste")
			(net "SW_P1V25_PEX0_BT")
		)
		(pad "2" smd circle
			(at 0.40005 0)
			(size 0 0)
			(layers "F.Cu" "F.Mask" "F.Paste")
			(net "SW_P1V25_PEX0_PH")
		)
	)
	(footprint ""
		(layer "F.Cu")
		(at 449.967858 -19.453098)
		(property "Reference" "R1738"
			(at 0 0 0)
			(layer "F.SilkS")
			(hide yes)
			(effects
				(font
					(size 1.27 1.27)
				)
			)
		)
		(property "Value" ""
			(at 0 0 0)
			(layer "F.Fab")
			(effects
				(font
					(size 1.27 1.27)
				)
			)
		)
		(duplicate_pad_numbers_are_jumpers no)
		(fp_line
			(start -0.7874 -0.4064)
			(end 0.7874 -0.4064)
			(stroke
				(width 0.1524)
				(type default)
			)
			(layer "F.SilkS")
		)
		(fp_line
			(start -0.7874 0.4064)
			(end -0.7874 -0.4064)
			(stroke
				(width 0.1524)
				(type default)
			)
			(layer "F.SilkS")
		)
		(fp_line
			(start 0.7874 -0.4064)
			(end 0.7874 0.4064)
			(stroke
				(width 0.1524)
				(type default)
			)
			(layer "F.SilkS")
		)
		(fp_line
			(start 0.7874 0.4064)
			(end -0.7874 0.4064)
			(stroke
				(width 0.1524)
				(type default)
			)
			(layer "F.SilkS")
		)
		(fp_line
			(start -0.67945 -0.305054)
			(end -0.12065 -0.305054)
			(stroke
				(width 0.1)
				(type default)
			)
			(layer "F.Fab")
		)
		(fp_line
			(start -0.67945 0.3048)
			(end -0.67945 -0.305054)
			(stroke
				(width 0.1)
				(type default)
			)
			(layer "F.Fab")
		)
		(fp_line
			(start -0.12065 -0.305054)
			(end -0.12065 -0.2794)
			(stroke
				(width 0.1)
				(type default)
			)
			(layer "F.Fab")
		)
		(fp_line
			(start -0.12065 -0.2794)
			(end 0.12065 -0.2794)
			(stroke
				(width 0.1)
				(type default)
			)
			(layer "F.Fab")
		)
		(fp_line
			(start -0.12065 0.2794)
			(end -0.12065 0.3048)
			(stroke
				(width 0.1)
				(type default)
			)
			(layer "F.Fab")
		)
		(fp_line
			(start -0.12065 0.3048)
			(end -0.67945 0.3048)
			(stroke
				(width 0.1)
				(type default)
			)
			(layer "F.Fab")
		)
		(fp_line
			(start 0.120396 0.2794)
			(end -0.12065 0.2794)
			(stroke
				(width 0.1)
				(type default)
			)
			(layer "F.Fab")
		)
		(fp_line
			(start 0.120396 0.3048)
			(end 0.120396 0.2794)
			(stroke
				(width 0.1)
				(type default)
			)
			(layer "F.Fab")
		)
		(fp_line
			(start 0.12065 -0.3048)
			(end 0.67945 -0.3048)
			(stroke
				(width 0.1)
				(type default)
			)
			(layer "F.Fab")
		)
		(fp_line
			(start 0.12065 -0.2794)
			(end 0.12065 -0.3048)
			(stroke
				(width 0.1)
				(type default)
			)
			(layer "F.Fab")
		)
		(fp_line
			(start 0.67945 -0.3048)
			(end 0.67945 0.3048)
			(stroke
				(width 0.1)
				(type default)
			)
			(layer "F.Fab")
		)
		(fp_line
			(start 0.67945 0.3048)
			(end 0.120396 0.3048)
			(stroke
				(width 0.1)
				(type default)
			)
			(layer "F.Fab")
		)
		(pad "1" smd circle
			(at -0.40005 0)
			(size 0 0)
			(layers "F.Cu" "F.Mask" "F.Paste")
			(net "SMB_ISO_SSD15_R_SDA")
		)
		(pad "2" smd circle
			(at 0.40005 0)
			(size 0 0)
			(layers "F.Cu" "F.Mask" "F.Paste")
			(net "SMB_ISO_SSD15_SDA")
		)
	)
	(footprint ""
		(layer "F.Cu")
		(at 214.310976 -368.035586 180)
		(property "Reference" "PR43"
			(at 0 0 180)
			(layer "F.SilkS")
			(hide yes)
			(effects
				(font
					(size 1.27 1.27)
				)
			)
		)
		(property "Value" ""
			(at 0 0 180)
			(layer "F.Fab")
			(effects
				(font
					(size 1.27 1.27)
				)
			)
		)
		(duplicate_pad_numbers_are_jumpers no)
		(fp_line
			(start 0.7874 0.4064)
			(end -0.7874 0.4064)
			(stroke
				(width 0.1524)
				(type default)
			)
			(layer "F.SilkS")
		)
		(fp_line
			(start 0.7874 -0.4064)
			(end 0.7874 0.4064)
			(stroke
				(width 0.1524)
				(type default)
			)
			(layer "F.SilkS")
		)
		(fp_line
			(start -0.7874 0.4064)
			(end -0.7874 -0.4064)
			(stroke
				(width 0.1524)
				(type default)
			)
			(layer "F.SilkS")
		)
		(fp_line
			(start -0.7874 -0.4064)
			(end 0.7874 -0.4064)
			(stroke
				(width 0.1524)
				(type default)
			)
			(layer "F.SilkS")
		)
		(fp_line
			(start 0.67945 0.3048)
			(end 0.120396 0.3048)
			(stroke
				(width 0.1)
				(type default)
			)
			(layer "F.Fab")
		)
		(fp_line
			(start 0.67945 -0.3048)
			(end 0.67945 0.3048)
			(stroke
				(width 0.1)
				(type default)
			)
			(layer "F.Fab")
		)
		(fp_line
			(start 0.12065 -0.2794)
			(end 0.12065 -0.3048)
			(stroke
				(width 0.1)
				(type default)
			)
			(layer "F.Fab")
		)
		(fp_line
			(start 0.12065 -0.3048)
			(end 0.67945 -0.3048)
			(stroke
				(width 0.1)
				(type default)
			)
			(layer "F.Fab")
		)
		(fp_line
			(start 0.120396 0.3048)
			(end 0.120396 0.2794)
			(stroke
				(width 0.1)
				(type default)
			)
			(layer "F.Fab")
		)
		(fp_line
			(start 0.120396 0.2794)
			(end -0.12065 0.2794)
			(stroke
				(width 0.1)
				(type default)
			)
			(layer "F.Fab")
		)
		(fp_line
			(start -0.12065 0.3048)
			(end -0.67945 0.3048)
			(stroke
				(width 0.1)
				(type default)
			)
			(layer "F.Fab")
		)
		(fp_line
			(start -0.12065 0.2794)
			(end -0.12065 0.3048)
			(stroke
				(width 0.1)
				(type default)
			)
			(layer "F.Fab")
		)
		(fp_line
			(start -0.12065 -0.2794)
			(end 0.12065 -0.2794)
			(stroke
				(width 0.1)
				(type default)
			)
			(layer "F.Fab")
		)
		(fp_line
			(start -0.12065 -0.305054)
			(end -0.12065 -0.2794)
			(stroke
				(width 0.1)
				(type default)
			)
			(layer "F.Fab")
		)
		(fp_line
			(start -0.67945 0.3048)
			(end -0.67945 -0.305054)
			(stroke
				(width 0.1)
				(type default)
			)
			(layer "F.Fab")
		)
		(fp_line
			(start -0.67945 -0.305054)
			(end -0.12065 -0.305054)
			(stroke
				(width 0.1)
				(type default)
			)
			(layer "F.Fab")
		)
		(pad "1" smd circle
			(at -0.40005 0 180)
			(size 0 0)
			(layers "F.Cu" "F.Mask" "F.Paste")
			(net "HSC_IMON")
		)
		(pad "2" smd circle
			(at 0.40005 0 180)
			(size 0 0)
			(layers "F.Cu" "F.Mask" "F.Paste")
			(net "AGND_HSC")
		)
	)
	(footprint ""
		(layer "F.Cu")
		(at 19.820128 -225.49993 180)
		(property "Reference" "JPEX0"
			(at -4.619498 -8.423148 0)
			(unlocked yes)
			(layer "F.SilkS")
			(effects
				(font
					(size 0.7874 0.5842)
					(thickness 0.1524)
				)
				(justify left)
			)
		)
		(property "Value" ""
			(at 0 0 180)
			(layer "F.Fab")
			(effects
				(font
					(size 1.27 1.27)
				)
			)
		)
		(duplicate_pad_numbers_are_jumpers no)
		(fp_line
			(start 12.46505 7.649972)
			(end -12.46505 7.649972)
			(stroke
				(width 0.1524)
				(type default)
			)
			(layer "F.SilkS")
		)
		(fp_line
			(start 12.46505 -7.649972)
			(end 12.46505 7.649972)
			(stroke
				(width 0.1524)
				(type default)
			)
			(layer "F.SilkS")
		)
		(fp_line
			(start 6.945122 7.649972)
			(end -6.945122 7.649972)
			(stroke
				(width 0.1524)
				(type default)
			)
			(layer "F.SilkS")
		)
		(fp_line
			(start 6.945122 -7.649972)
			(end 6.945122 7.649972)
			(stroke
				(width 0.1524)
				(type default)
			)
			(layer "F.SilkS")
		)
		(fp_line
			(start 6.945122 -7.649972)
			(end 0 -7.649972)
			(stroke
				(width 0.1524)
				(type default)
			)
			(layer "F.SilkS")
		)
		(fp_line
			(start 0 -7.649972)
			(end 12.46505 -7.649972)
			(stroke
				(width 0.1524)
				(type default)
			)
			(layer "F.SilkS")
		)
		(fp_line
			(start -6.945122 -7.649972)
			(end 0 -7.649972)
			(stroke
				(width 0.1524)
				(type default)
			)
			(layer "F.SilkS")
		)
		(fp_line
			(start -6.945122 -7.649972)
			(end -6.945122 7.649972)
			(stroke
				(width 0.1524)
				(type default)
			)
			(layer "F.SilkS")
		)
		(fp_line
			(start -12.46505 7.649972)
			(end -12.46505 -7.649972)
			(stroke
				(width 0.1524)
				(type default)
			)
			(layer "F.SilkS")
		)
		(fp_line
			(start -12.46505 -7.649972)
			(end 0 -7.649972)
			(stroke
				(width 0.1524)
				(type default)
			)
			(layer "F.SilkS")
		)
		(fp_poly
			(pts
				(xy -7.112 -4.445) (xy -8.128 -4.953) (xy -8.128 -3.937)
			)
			(stroke
				(width 0)
				(type default)
			)
			(fill yes)
			(layer "F.SilkS")
		)
		(fp_line
			(start 6.945122 7.649972)
			(end -6.945122 7.649972)
			(stroke
				(width 0.1)
				(type default)
			)
			(layer "F.Fab")
		)
		(fp_line
			(start 6.945122 -7.649972)
			(end 6.945122 7.649972)
			(stroke
				(width 0.1)
				(type default)
			)
			(layer "F.Fab")
		)
		(fp_line
			(start -6.945122 7.649972)
			(end -6.945122 -7.649972)
			(stroke
				(width 0.1)
				(type default)
			)
			(layer "F.Fab")
		)
		(fp_line
			(start -6.945122 -7.649972)
			(end 6.945122 -7.649972)
			(stroke
				(width 0.1)
				(type default)
			)
			(layer "F.Fab")
		)
		(fp_poly
			(pts
				(xy -7.112 -4.445) (xy -8.128 -4.953) (xy -8.128 -3.937)
			)
			(stroke
				(width 0)
				(type default)
			)
			(fill yes)
			(layer "F.Fab")
		)
		(fp_text user "9"
			(at 7.51713 4.1656 90)
			(unlocked yes)
			(layer "F.SilkS")
			(effects
				(font
					(size 0.7874 0.5842)
					(thickness 0.1524)
				)
				(justify left)
			)
		)
		(fp_text user "16"
			(at 7.49173 -5.2324 90)
			(unlocked yes)
			(layer "F.SilkS")
			(effects
				(font
					(size 0.7874 0.5842)
					(thickness 0.1524)
				)
				(justify left)
			)
		)
		(fp_text user "8"
			(at -7.77367 4.2164 90)
			(unlocked yes)
			(layer "F.SilkS")
			(effects
				(font
					(size 0.7874 0.5842)
					(thickness 0.1524)
				)
				(justify left)
			)
		)
		(fp_text user "9"
			(at 7.51713 4.1656 90)
			(unlocked yes)
			(layer "F.Fab")
			(effects
				(font
					(size 0.7874 0.5842)
					(thickness 0.1524)
				)
				(justify left)
			)
		)
		(fp_text user "16"
			(at 7.49173 -5.2324 90)
			(unlocked yes)
			(layer "F.Fab")
			(effects
				(font
					(size 0.7874 0.5842)
					(thickness 0.1524)
				)
				(justify left)
			)
		)
		(fp_text user "8"
			(at -7.77367 4.2164 90)
			(unlocked yes)
			(layer "F.Fab")
			(effects
				(font
					(size 0.7874 0.5842)
					(thickness 0.1524)
				)
				(justify left)
			)
		)
		(pad "1" smd rect
			(at -4.800092 -4.445 90)
			(size 0.508 1.524)
			(layers "F.Cu" "F.Mask" "F.Paste")
			(net "SPI_PEX0_SDIO3_R1")
		)
		(pad "2" smd rect
			(at -4.800092 -3.175 90)
			(size 0.508 1.524)
			(layers "F.Cu" "F.Mask" "F.Paste")
			(net "P1V8_PEX")
		)
		(pad "3" smd rect
			(at -4.800092 -1.905 90)
			(size 0.508 1.524)
			(layers "F.Cu" "F.Mask" "F.Paste")
			(net "SPI_PEX0_RST_R_N")
		)
		(pad "4" smd rect
			(at -4.800092 -0.635 90)
			(size 0.508 1.524)
			(layers "F.Cu" "F.Mask" "F.Paste")
			(net "Net_2684")
		)
		(pad "5" smd rect
			(at -4.800092 0.635 90)
			(size 0.508 1.524)
			(layers "F.Cu" "F.Mask" "F.Paste")
			(net "Net_2683")
		)
		(pad "6" smd rect
			(at -4.800092 1.905 90)
			(size 0.508 1.524)
			(layers "F.Cu" "F.Mask" "F.Paste")
			(net "Net_2682")
		)
		(pad "7" smd rect
			(at -4.800092 3.175 90)
			(size 0.508 1.524)
			(layers "F.Cu" "F.Mask" "F.Paste")
			(net "SPI_PEX0_CS_MUX_R_N")
		)
		(pad "8" smd rect
			(at -4.800092 4.445 90)
			(size 0.508 1.524)
			(layers "F.Cu" "F.Mask" "F.Paste")
			(net "SPI_PEX0_SDIO1_MUX_R")
		)
		(pad "9" smd rect
			(at 4.800092 4.445 90)
			(size 0.508 1.524)
			(layers "F.Cu" "F.Mask" "F.Paste")
			(net "SPI_PEX0_SDIO2_R1")
		)
		(pad "10" smd rect
			(at 4.800092 3.175 90)
			(size 0.508 1.524)
			(layers "F.Cu" "F.Mask" "F.Paste")
			(net "GND")
		)
		(pad "11" smd rect
			(at 4.800092 1.905 90)
			(size 0.508 1.524)
			(layers "F.Cu" "F.Mask" "F.Paste")
			(net "Net_2685")
		)
		(pad "12" smd rect
			(at 4.800092 0.635 90)
			(size 0.508 1.524)
			(layers "F.Cu" "F.Mask" "F.Paste")
			(net "Net_2686")
		)
		(pad "13" smd rect
			(at 4.800092 -0.635 90)
			(size 0.508 1.524)
			(layers "F.Cu" "F.Mask" "F.Paste")
			(net "Net_2687")
		)
		(pad "14" smd rect
			(at 4.800092 -1.905 90)
			(size 0.508 1.524)
			(layers "F.Cu" "F.Mask" "F.Paste")
			(net "Net_2688")
		)
		(pad "15" smd rect
			(at 4.800092 -3.175 90)
			(size 0.508 1.524)
			(layers "F.Cu" "F.Mask" "F.Paste")
			(net "SPI_PEX0_SDIO0_MUX_R")
		)
		(pad "16" smd rect
			(at 4.800092 -4.445 90)
			(size 0.508 1.524)
			(layers "F.Cu" "F.Mask" "F.Paste")
			(net "SPI_PEX0_CLK_MUX_R")
		)
	)
	(footprint ""
		(layer "F.Cu")
		(at 336.931 -238.633 -90)
		(property "Reference" "R1795"
			(at 0 0 270)
			(layer "F.SilkS")
			(hide yes)
			(effects
				(font
					(size 1.27 1.27)
				)
			)
		)
		(property "Value" ""
			(at 0 0 270)
			(layer "F.Fab")
			(effects
				(font
					(size 1.27 1.27)
				)
			)
		)
		(duplicate_pad_numbers_are_jumpers no)
		(fp_line
			(start -0.7874 0.4064)
			(end -0.7874 -0.4064)
			(stroke
				(width 0.1524)
				(type default)
			)
			(layer "F.SilkS")
		)
		(fp_line
			(start 0.7874 0.4064)
			(end -0.7874 0.4064)
			(stroke
				(width 0.1524)
				(type default)
			)
			(layer "F.SilkS")
		)
		(fp_line
			(start -0.7874 -0.4064)
			(end 0.7874 -0.4064)
			(stroke
				(width 0.1524)
				(type default)
			)
			(layer "F.SilkS")
		)
		(fp_line
			(start 0.7874 -0.4064)
			(end 0.7874 0.4064)
			(stroke
				(width 0.1524)
				(type default)
			)
			(layer "F.SilkS")
		)
		(fp_line
			(start -0.67945 0.3048)
			(end -0.67945 -0.305054)
			(stroke
				(width 0.1)
				(type default)
			)
			(layer "F.Fab")
		)
		(fp_line
			(start -0.12065 0.3048)
			(end -0.67945 0.3048)
			(stroke
				(width 0.1)
				(type default)
			)
			(layer "F.Fab")
		)
		(fp_line
			(start 0.120396 0.3048)
			(end 0.120396 0.2794)
			(stroke
				(width 0.1)
				(type default)
			)
			(layer "F.Fab")
		)
		(fp_line
			(start 0.67945 0.3048)
			(end 0.120396 0.3048)
			(stroke
				(width 0.1)
				(type default)
			)
			(layer "F.Fab")
		)
		(fp_line
			(start -0.12065 0.2794)
			(end -0.12065 0.3048)
			(stroke
				(width 0.1)
				(type default)
			)
			(layer "F.Fab")
		)
		(fp_line
			(start 0.120396 0.2794)
			(end -0.12065 0.2794)
			(stroke
				(width 0.1)
				(type default)
			)
			(layer "F.Fab")
		)
		(fp_line
			(start -0.12065 -0.2794)
			(end 0.12065 -0.2794)
			(stroke
				(width 0.1)
				(type default)
			)
			(layer "F.Fab")
		)
		(fp_line
			(start 0.12065 -0.2794)
			(end 0.12065 -0.3048)
			(stroke
				(width 0.1)
				(type default)
			)
			(layer "F.Fab")
		)
		(fp_line
			(start 0.12065 -0.3048)
			(end 0.67945 -0.3048)
			(stroke
				(width 0.1)
				(type default)
			)
			(layer "F.Fab")
		)
		(fp_line
			(start 0.67945 -0.3048)
			(end 0.67945 0.3048)
			(stroke
				(width 0.1)
				(type default)
			)
			(layer "F.Fab")
		)
		(fp_line
			(start -0.67945 -0.305054)
			(end -0.12065 -0.305054)
			(stroke
				(width 0.1)
				(type default)
			)
			(layer "F.Fab")
		)
		(fp_line
			(start -0.12065 -0.305054)
			(end -0.12065 -0.2794)
			(stroke
				(width 0.1)
				(type default)
			)
			(layer "F.Fab")
		)
		(pad "1" smd circle
			(at -0.40005 0 270)
			(size 0 0)
			(layers "F.Cu" "F.Mask" "F.Paste")
			(net "MB_SWB_PWR_EN_ISO")
		)
		(pad "2" smd circle
			(at 0.40005 0 270)
			(size 0 0)
			(layers "F.Cu" "F.Mask" "F.Paste")
			(net "MB_SWB_PWR_EN_ISO_R")
		)
	)
)
